(kicad_pcb
	(version 20260206)
	(generator "pcbnew")
	(generator_version "10.0")
	(general
		(thickness 1.6)
		(legacy_teardrops no)
	)
	(paper "A4")
	(title_block
		(title "fcb — 12433-1M.1206WZS1330.brd")
		(comment 1 "Open Vault / Knox (Wiwynn) / footprints 421-428 of 495")
	)
	(layers
		(0 "F.Cu" signal "TOP")
		(4 "In1.Cu" signal "L2GND")
		(6 "In2.Cu" signal "L3VCC")
		(2 "B.Cu" signal "BOTTOM")
		(9 "F.Adhes" user "F.Adhesive")
		(11 "B.Adhes" user "B.Adhesive")
		(13 "F.Paste" user "Package Geometry/Pastemask Top")
		(15 "B.Paste" user "Package Geometry/Pastemask Bottom")
		(5 "F.SilkS" user "Ref Des/Silkscreen Top")
		(7 "B.SilkS" user "Ref Des/Silkscreen Bottom")
		(1 "F.Mask" user "Board Geometry/Soldermask Top")
		(3 "B.Mask" user "Board Geometry/Soldermask Bottom")
		(17 "Dwgs.User" user "User.Drawings")
		(19 "Cmts.User" user "User.Comments")
		(21 "Eco1.User" user "User.Eco1")
		(23 "Eco2.User" user "User.Eco2")
		(25 "Edge.Cuts" user "Board Geometry/Outline")
		(27 "Margin" user)
		(31 "F.CrtYd" user "Package Geometry/Place Bound Top")
		(29 "B.CrtYd" user "Package Geometry/Place Bound Bottom")
		(35 "F.Fab" user "Ref Des/Assembly Top")
		(33 "B.Fab" user "Ref Des/Assembly Bottom")
	)
	(footprint ""
		(layer "F.Cu")
		(at 18.8214 -145.6436 180)
		(property "Reference" "PC91"
			(at 0 0 180)
			(layer "F.SilkS")
			(hide yes)
			(effects
				(font
					(size 1.27 1.27)
				)
			)
		)
		(property "Value" "SCD01U50V3KX-4GP"
			(at 0 -2.8194 180)
			(unlocked yes)
			(layer "F.Fab")
			(hide yes)
			(effects
				(font
					(size 1.016 1.016)
					(thickness 0.1524)
				)
			)
		)
		(property "Device Type" "C603H36"
			(at 0 -4.3434 180)
			(unlocked yes)
			(layer "F.Fab")
			(hide yes)
			(effects
				(font
					(size 1.016 1.016)
					(thickness 0.1524)
				)
			)
		)
		(duplicate_pad_numbers_are_jumpers no)
		(fp_line
			(start 0.508 0)
			(end -0.508 0)
			(stroke
				(width 0.2032)
				(type default)
			)
			(layer "F.SilkS")
		)
		(fp_rect
			(start -0.5842 1.3335)
			(end 0.5842 -1.3335)
			(stroke
				(width 0)
				(type default)
			)
			(fill no)
			(layer "F.CrtYd")
		)
		(fp_rect
			(start -0.5842 1.3335)
			(end 0.5842 -1.3335)
			(stroke
				(width 0)
				(type default)
			)
			(fill no)
			(layer "F.Fab")
		)
		(pad "1" smd custom
			(at 0 -0.762 180)
			(size 0.2159 0.2159)
			(layers "F.Cu" "F.Mask" "F.Paste")
			(net "P12VU_2490_TIMER")
			(options
				(clearance outline)
				(anchor circle)
			)
			(primitives
				(gr_poly
					(pts
						(arc
							(start -0.3302 -0.4318)
							(mid -0.402042 -0.402042)
							(end -0.4318 -0.3302)
						)
						(arc
							(start -0.4318 0.3302)
							(mid -0.402042 0.402042)
							(end -0.3302 0.4318)
						)
						(arc
							(start 0.3302 0.4318)
							(mid 0.402042 0.402042)
							(end 0.4318 0.3302)
						)
						(arc
							(start 0.4318 -0.3302)
							(mid 0.402042 -0.402042)
							(end 0.3302 -0.4318)
						)
					)
					(width 0)
					(fill yes)
				)
			)
		)
		(pad "2" smd custom
			(at 0 0.762 180)
			(size 0.2159 0.2159)
			(layers "F.Cu" "F.Mask" "F.Paste")
			(net "GND")
			(options
				(clearance outline)
				(anchor circle)
			)
			(primitives
				(gr_poly
					(pts
						(arc
							(start -0.3302 -0.4318)
							(mid -0.402042 -0.402042)
							(end -0.4318 -0.3302)
						)
						(arc
							(start -0.4318 0.3302)
							(mid -0.402042 0.402042)
							(end -0.3302 0.4318)
						)
						(arc
							(start 0.3302 0.4318)
							(mid 0.402042 0.402042)
							(end 0.4318 0.3302)
						)
						(arc
							(start 0.4318 -0.3302)
							(mid 0.402042 -0.402042)
							(end 0.3302 -0.4318)
						)
					)
					(width 0)
					(fill yes)
				)
			)
		)
	)
	(footprint ""
		(layer "F.Cu")
		(at 9.906 -261.112 180)
		(property "Reference" "R125"
			(at 0 0 180)
			(layer "F.SilkS")
			(hide yes)
			(effects
				(font
					(size 1.27 1.27)
				)
			)
		)
		(property "Value" "1K8R6J-GP"
			(at -0.0508 -4.8514 180)
			(unlocked yes)
			(layer "F.Fab")
			(hide yes)
			(effects
				(font
					(size 1.016 1.016)
					(thickness 0.1524)
				)
			)
		)
		(property "Device Type" "R1206H28"
			(at 0 -6.3754 180)
			(unlocked yes)
			(layer "F.Fab")
			(hide yes)
			(effects
				(font
					(size 1.016 1.016)
					(thickness 0.1524)
				)
			)
		)
		(duplicate_pad_numbers_are_jumpers no)
		(fp_line
			(start 1.016 2.2352)
			(end -1.016 2.2352)
			(stroke
				(width 0.1524)
				(type default)
			)
			(layer "F.SilkS")
		)
		(fp_line
			(start 1.016 -2.2352)
			(end 1.016 2.2352)
			(stroke
				(width 0.1524)
				(type default)
			)
			(layer "F.SilkS")
		)
		(fp_line
			(start -1.016 2.2352)
			(end -1.016 -2.2352)
			(stroke
				(width 0.1524)
				(type default)
			)
			(layer "F.SilkS")
		)
		(fp_line
			(start -1.016 -2.2352)
			(end 1.016 -2.2352)
			(stroke
				(width 0.1524)
				(type default)
			)
			(layer "F.SilkS")
		)
		(fp_rect
			(start -1.0922 2.3114)
			(end 1.0922 -2.3114)
			(stroke
				(width 0)
				(type default)
			)
			(fill no)
			(layer "F.CrtYd")
		)
		(fp_poly
			(pts
				(xy -1.0922 -2.3114) (xy 1.0922 -2.3114) (xy 1.0922 2.3114) (xy -1.0922 2.3114)
			)
			(stroke
				(width 0)
				(type default)
			)
			(fill no)
			(layer "F.Fab")
		)
		(pad "1" smd rect
			(at 0 -1.397 180)
			(size 1.651 1.27)
			(layers "F.Cu" "F.Mask" "F.Paste")
			(net "P12V")
		)
		(pad "2" smd rect
			(at 0 1.397 180)
			(size 1.651 1.27)
			(layers "F.Cu" "F.Mask" "F.Paste")
			(net "LED_DR_LED2_BLUE")
		)
	)
	(footprint ""
		(layer "F.Cu")
		(at 35.687 -240.3094 180)
		(property "Reference" "R56"
			(at 0 0 180)
			(layer "F.SilkS")
			(hide yes)
			(effects
				(font
					(size 1.27 1.27)
				)
			)
		)
		(property "Value" "4K7R2J-2-GP"
			(at 0.064008 -3.993896 180)
			(unlocked yes)
			(layer "F.Fab")
			(hide yes)
			(effects
				(font
					(size 1.016 1.016)
					(thickness 0.1524)
				)
			)
		)
		(property "Device Type" "R402H16"
			(at 0.064008 -5.517896 180)
			(unlocked yes)
			(layer "F.Fab")
			(hide yes)
			(effects
				(font
					(size 1.016 1.016)
					(thickness 0.1524)
				)
			)
		)
		(duplicate_pad_numbers_are_jumpers no)
		(fp_line
			(start 0.508 -0.9398)
			(end -0.508 -0.9398)
			(stroke
				(width 0.1524)
				(type default)
			)
			(layer "F.SilkS")
		)
		(fp_line
			(start -0.508 -0.9398)
			(end -0.508 0.9398)
			(stroke
				(width 0.1524)
				(type default)
			)
			(layer "F.SilkS")
		)
		(fp_rect
			(start -0.508 0.9398)
			(end 0.508 -0.9398)
			(stroke
				(width 0)
				(type default)
			)
			(fill no)
			(layer "F.CrtYd")
		)
		(fp_rect
			(start -0.508 0.9398)
			(end 0.508 -0.9398)
			(stroke
				(width 0)
				(type default)
			)
			(fill no)
			(layer "F.Fab")
		)
		(pad "1" smd custom
			(at 0 -0.4445 180)
			(size 0.1397 0.1397)
			(layers "F.Cu" "F.Mask" "F.Paste")
			(net "GND")
			(options
				(clearance outline)
				(anchor circle)
			)
			(primitives
				(gr_poly
					(pts
						(arc
							(start -0.1778 -0.2794)
							(mid -0.249642 -0.249642)
							(end -0.2794 -0.1778)
						)
						(arc
							(start -0.2794 0.1778)
							(mid -0.249642 0.249642)
							(end -0.1778 0.2794)
						)
						(arc
							(start 0.1778 0.2794)
							(mid 0.249642 0.249642)
							(end 0.2794 0.1778)
						)
						(arc
							(start 0.2794 -0.1778)
							(mid 0.249642 -0.249642)
							(end 0.1778 -0.2794)
						)
					)
					(width 0)
					(fill yes)
				)
			)
		)
		(pad "2" smd custom
			(at 0 0.4445 180)
			(size 0.1397 0.1397)
			(layers "F.Cu" "F.Mask" "F.Paste")
			(net "LED_DRV_A2")
			(options
				(clearance outline)
				(anchor circle)
			)
			(primitives
				(gr_poly
					(pts
						(arc
							(start -0.1778 -0.2794)
							(mid -0.249642 -0.249642)
							(end -0.2794 -0.1778)
						)
						(arc
							(start -0.2794 0.1778)
							(mid -0.249642 0.249642)
							(end -0.1778 0.2794)
						)
						(arc
							(start 0.1778 0.2794)
							(mid 0.249642 0.249642)
							(end 0.2794 0.1778)
						)
						(arc
							(start 0.2794 -0.1778)
							(mid 0.249642 -0.249642)
							(end 0.1778 -0.2794)
						)
					)
					(width 0)
					(fill yes)
				)
			)
		)
	)
	(footprint ""
		(layer "F.Cu")
		(at 16.4592 -260.35 -90)
		(property "Reference" "R84"
			(at 0 0 270)
			(layer "F.SilkS")
			(hide yes)
			(effects
				(font
					(size 1.27 1.27)
				)
			)
		)
		(property "Value" "27KR3F-GP"
			(at -0.0254 -2.5146 270)
			(unlocked yes)
			(layer "F.Fab")
			(hide yes)
			(effects
				(font
					(size 1.016 1.016)
					(thickness 0.1524)
				)
			)
		)
		(property "Device Type" "R603H22"
			(at -0.0254 -4.0386 270)
			(unlocked yes)
			(layer "F.Fab")
			(hide yes)
			(effects
				(font
					(size 1.016 1.016)
					(thickness 0.1524)
				)
			)
		)
		(duplicate_pad_numbers_are_jumpers no)
		(fp_line
			(start -0.4826 0)
			(end -0.2032 0)
			(stroke
				(width 0.2032)
				(type default)
			)
			(layer "F.SilkS")
		)
		(fp_line
			(start 0.2032 0)
			(end 0.4826 0)
			(stroke
				(width 0.2032)
				(type default)
			)
			(layer "F.SilkS")
		)
		(fp_rect
			(start -0.5842 1.3335)
			(end 0.5842 -1.3335)
			(stroke
				(width 0)
				(type default)
			)
			(fill no)
			(layer "F.CrtYd")
		)
		(fp_rect
			(start -0.5842 1.3335)
			(end 0.5842 -1.3335)
			(stroke
				(width 0)
				(type default)
			)
			(fill no)
			(layer "F.Fab")
		)
		(pad "1" smd custom
			(at 0 -0.762 270)
			(size 0.2159 0.2159)
			(layers "F.Cu" "F.Mask" "F.Paste")
			(net "FAN_TACH6")
			(options
				(clearance outline)
				(anchor circle)
			)
			(primitives
				(gr_poly
					(pts
						(arc
							(start -0.3302 -0.4318)
							(mid -0.402042 -0.402042)
							(end -0.4318 -0.3302)
						)
						(arc
							(start -0.4318 0.3302)
							(mid -0.402042 0.402042)
							(end -0.3302 0.4318)
						)
						(arc
							(start 0.3302 0.4318)
							(mid 0.402042 0.402042)
							(end 0.4318 0.3302)
						)
						(arc
							(start 0.4318 -0.3302)
							(mid 0.402042 -0.402042)
							(end 0.3302 -0.4318)
						)
					)
					(width 0)
					(fill yes)
				)
			)
		)
		(pad "2" smd custom
			(at 0 0.762 270)
			(size 0.2159 0.2159)
			(layers "F.Cu" "F.Mask" "F.Paste")
			(net "FANIN_6")
			(options
				(clearance outline)
				(anchor circle)
			)
			(primitives
				(gr_poly
					(pts
						(arc
							(start -0.3302 -0.4318)
							(mid -0.402042 -0.402042)
							(end -0.4318 -0.3302)
						)
						(arc
							(start -0.4318 0.3302)
							(mid -0.402042 0.402042)
							(end -0.3302 0.4318)
						)
						(arc
							(start 0.3302 0.4318)
							(mid 0.402042 0.402042)
							(end 0.4318 0.3302)
						)
						(arc
							(start 0.4318 -0.3302)
							(mid 0.402042 -0.402042)
							(end 0.3302 -0.4318)
						)
					)
					(width 0)
					(fill yes)
				)
			)
		)
	)
	(footprint ""
		(layer "F.Cu")
		(at 14.4526 -60.5282)
		(property "Reference" "R362"
			(at 0 0 0)
			(layer "F.SilkS")
			(hide yes)
			(effects
				(font
					(size 1.27 1.27)
				)
			)
		)
		(property "Value" "100R2J-2-GP"
			(at 0.064008 -3.993896 0)
			(unlocked yes)
			(layer "F.Fab")
			(hide yes)
			(effects
				(font
					(size 1.016 1.016)
					(thickness 0.1524)
				)
			)
		)
		(property "Device Type" "R402H14"
			(at 0.064008 -5.517896 0)
			(unlocked yes)
			(layer "F.Fab")
			(hide yes)
			(effects
				(font
					(size 1.016 1.016)
					(thickness 0.1524)
				)
			)
		)
		(duplicate_pad_numbers_are_jumpers no)
		(fp_line
			(start -0.508 -0.9398)
			(end -0.508 0.9398)
			(stroke
				(width 0.1524)
				(type default)
			)
			(layer "F.SilkS")
		)
		(fp_line
			(start 0.508 -0.9398)
			(end -0.508 -0.9398)
			(stroke
				(width 0.1524)
				(type default)
			)
			(layer "F.SilkS")
		)
		(fp_rect
			(start -0.508 0.9398)
			(end 0.508 -0.9398)
			(stroke
				(width 0)
				(type default)
			)
			(fill no)
			(layer "F.CrtYd")
		)
		(fp_rect
			(start -0.508 0.9398)
			(end 0.508 -0.9398)
			(stroke
				(width 0)
				(type default)
			)
			(fill no)
			(layer "F.Fab")
		)
		(pad "1" smd custom
			(at 0 -0.4445)
			(size 0.1397 0.1397)
			(layers "F.Cu" "F.Mask" "F.Paste")
			(net "UPPER_TRAY_ID")
			(options
				(clearance outline)
				(anchor circle)
			)
			(primitives
				(gr_poly
					(pts
						(arc
							(start -0.1778 -0.2794)
							(mid -0.249642 -0.249642)
							(end -0.2794 -0.1778)
						)
						(arc
							(start -0.2794 0.1778)
							(mid -0.249642 0.249642)
							(end -0.1778 0.2794)
						)
						(arc
							(start 0.1778 0.2794)
							(mid 0.249642 0.249642)
							(end 0.2794 0.1778)
						)
						(arc
							(start 0.2794 -0.1778)
							(mid 0.249642 -0.249642)
							(end 0.1778 -0.2794)
						)
					)
					(width 0)
					(fill yes)
				)
			)
		)
		(pad "2" smd custom
			(at 0 0.4445)
			(size 0.1397 0.1397)
			(layers "F.Cu" "F.Mask" "F.Paste")
			(net "GND")
			(options
				(clearance outline)
				(anchor circle)
			)
			(primitives
				(gr_poly
					(pts
						(arc
							(start -0.1778 -0.2794)
							(mid -0.249642 -0.249642)
							(end -0.2794 -0.1778)
						)
						(arc
							(start -0.2794 0.1778)
							(mid -0.249642 0.249642)
							(end -0.1778 0.2794)
						)
						(arc
							(start 0.1778 0.2794)
							(mid 0.249642 0.249642)
							(end 0.2794 0.1778)
						)
						(arc
							(start 0.2794 -0.1778)
							(mid 0.249642 -0.249642)
							(end 0.1778 -0.2794)
						)
					)
					(width 0)
					(fill yes)
				)
			)
		)
	)
	(footprint ""
		(layer "F.Cu")
		(at 7.8232 -83.439 90)
		(property "Reference" "R123"
			(at 0 0 90)
			(layer "F.SilkS")
			(hide yes)
			(effects
				(font
					(size 1.27 1.27)
				)
			)
		)
		(property "Value" "1K8R6J-GP"
			(at -0.0508 -4.8514 90)
			(unlocked yes)
			(layer "F.Fab")
			(hide yes)
			(effects
				(font
					(size 1.016 1.016)
					(thickness 0.1524)
				)
			)
		)
		(property "Device Type" "R1206H28"
			(at 0 -6.3754 90)
			(unlocked yes)
			(layer "F.Fab")
			(hide yes)
			(effects
				(font
					(size 1.016 1.016)
					(thickness 0.1524)
				)
			)
		)
		(duplicate_pad_numbers_are_jumpers no)
		(fp_line
			(start 1.016 -2.2352)
			(end 1.016 2.2352)
			(stroke
				(width 0.1524)
				(type default)
			)
			(layer "F.SilkS")
		)
		(fp_line
			(start -1.016 -2.2352)
			(end 1.016 -2.2352)
			(stroke
				(width 0.1524)
				(type default)
			)
			(layer "F.SilkS")
		)
		(fp_line
			(start 1.016 2.2352)
			(end -1.016 2.2352)
			(stroke
				(width 0.1524)
				(type default)
			)
			(layer "F.SilkS")
		)
		(fp_line
			(start -1.016 2.2352)
			(end -1.016 -2.2352)
			(stroke
				(width 0.1524)
				(type default)
			)
			(layer "F.SilkS")
		)
		(fp_rect
			(start -1.0922 2.3114)
			(end 1.0922 -2.3114)
			(stroke
				(width 0)
				(type default)
			)
			(fill no)
			(layer "F.CrtYd")
		)
		(fp_poly
			(pts
				(xy -1.0922 -2.3114) (xy 1.0922 -2.3114) (xy 1.0922 2.3114) (xy -1.0922 2.3114)
			)
			(stroke
				(width 0)
				(type default)
			)
			(fill no)
			(layer "F.Fab")
		)
		(pad "1" smd rect
			(at 0 -1.397 90)
			(size 1.651 1.27)
			(layers "F.Cu" "F.Mask" "F.Paste")
			(net "P12V")
		)
		(pad "2" smd rect
			(at 0 1.397 90)
			(size 1.651 1.27)
			(layers "F.Cu" "F.Mask" "F.Paste")
			(net "LED_DR_LED4_BLUE")
		)
	)
	(footprint ""
		(layer "F.Cu")
		(at 23.48611 -154.602434)
		(property "Reference" "R4"
			(at 0 0 0)
			(layer "F.SilkS")
			(hide yes)
			(effects
				(font
					(size 1.27 1.27)
				)
			)
		)
		(property "Value" "0R2J-2-GP"
			(at 0.064008 -3.993896 0)
			(unlocked yes)
			(layer "F.Fab")
			(hide yes)
			(effects
				(font
					(size 1.016 1.016)
					(thickness 0.1524)
				)
			)
		)
		(property "Device Type" "R402H16"
			(at 0.064008 -5.517896 0)
			(unlocked yes)
			(layer "F.Fab")
			(hide yes)
			(effects
				(font
					(size 1.016 1.016)
					(thickness 0.1524)
				)
			)
		)
		(duplicate_pad_numbers_are_jumpers no)
		(fp_line
			(start -0.508 -0.9398)
			(end -0.508 0.9398)
			(stroke
				(width 0.1524)
				(type default)
			)
			(layer "F.SilkS")
		)
		(fp_line
			(start 0.508 -0.9398)
			(end -0.508 -0.9398)
			(stroke
				(width 0.1524)
				(type default)
			)
			(layer "F.SilkS")
		)
		(fp_rect
			(start -0.508 0.9398)
			(end 0.508 -0.9398)
			(stroke
				(width 0)
				(type default)
			)
			(fill no)
			(layer "F.CrtYd")
		)
		(fp_rect
			(start -0.508 0.9398)
			(end 0.508 -0.9398)
			(stroke
				(width 0)
				(type default)
			)
			(fill no)
			(layer "F.Fab")
		)
		(pad "1" smd custom
			(at 0 -0.4445)
			(size 0.1397 0.1397)
			(layers "F.Cu" "F.Mask" "F.Paste")
			(net "NCT7904_TMPALM")
			(options
				(clearance outline)
				(anchor circle)
			)
			(primitives
				(gr_poly
					(pts
						(arc
							(start -0.1778 -0.2794)
							(mid -0.249642 -0.249642)
							(end -0.2794 -0.1778)
						)
						(arc
							(start -0.2794 0.1778)
							(mid -0.249642 0.249642)
							(end -0.1778 0.2794)
						)
						(arc
							(start 0.1778 0.2794)
							(mid 0.249642 0.249642)
							(end 0.2794 0.1778)
						)
						(arc
							(start 0.2794 -0.1778)
							(mid 0.249642 -0.249642)
							(end 0.1778 -0.2794)
						)
					)
					(width 0)
					(fill yes)
				)
			)
		)
		(pad "2" smd custom
			(at 0 0.4445)
			(size 0.1397 0.1397)
			(layers "F.Cu" "F.Mask" "F.Paste")
			(net "TEMP_ALM#")
			(options
				(clearance outline)
				(anchor circle)
			)
			(primitives
				(gr_poly
					(pts
						(arc
							(start -0.1778 -0.2794)
							(mid -0.249642 -0.249642)
							(end -0.2794 -0.1778)
						)
						(arc
							(start -0.2794 0.1778)
							(mid -0.249642 0.249642)
							(end -0.1778 0.2794)
						)
						(arc
							(start 0.1778 0.2794)
							(mid 0.249642 0.249642)
							(end 0.2794 0.1778)
						)
						(arc
							(start 0.2794 -0.1778)
							(mid 0.249642 -0.249642)
							(end 0.1778 -0.2794)
						)
					)
					(width 0)
					(fill yes)
				)
			)
		)
	)
	(footprint ""
		(layer "F.Cu")
		(at 44.704 -158.5722 -90)
		(property "Reference" "R14"
			(at 0 0 270)
			(layer "F.SilkS")
			(hide yes)
			(effects
				(font
					(size 1.27 1.27)
				)
			)
		)
		(property "Value" "110KR2F-L-GP"
			(at 0.064008 -3.993896 270)
			(unlocked yes)
			(layer "F.Fab")
			(hide yes)
			(effects
				(font
					(size 1.016 1.016)
					(thickness 0.1524)
				)
			)
		)
		(property "Device Type" "R402H16"
			(at 0.064008 -5.517896 270)
			(unlocked yes)
			(layer "F.Fab")
			(hide yes)
			(effects
				(font
					(size 1.016 1.016)
					(thickness 0.1524)
				)
			)
		)
		(duplicate_pad_numbers_are_jumpers no)
		(fp_line
			(start -0.508 -0.9398)
			(end -0.508 0.9398)
			(stroke
				(width 0.1524)
				(type default)
			)
			(layer "F.SilkS")
		)
		(fp_line
			(start 0.508 -0.9398)
			(end -0.508 -0.9398)
			(stroke
				(width 0.1524)
				(type default)
			)
			(layer "F.SilkS")
		)
		(fp_rect
			(start -0.508 0.9398)
			(end 0.508 -0.9398)
			(stroke
				(width 0)
				(type default)
			)
			(fill no)
			(layer "F.CrtYd")
		)
		(fp_rect
			(start -0.508 0.9398)
			(end 0.508 -0.9398)
			(stroke
				(width 0)
				(type default)
			)
			(fill no)
			(layer "F.Fab")
		)
		(pad "1" smd custom
			(at 0 -0.4445 270)
			(size 0.1397 0.1397)
			(layers "F.Cu" "F.Mask" "F.Paste")
			(net "P12V_AUX")
			(options
				(clearance outline)
				(anchor circle)
			)
			(primitives
				(gr_poly
					(pts
						(arc
							(start -0.1778 -0.2794)
							(mid -0.249642 -0.249642)
							(end -0.2794 -0.1778)
						)
						(arc
							(start -0.2794 0.1778)
							(mid -0.249642 0.249642)
							(end -0.1778 0.2794)
						)
						(arc
							(start 0.1778 0.2794)
							(mid 0.249642 0.249642)
							(end 0.2794 0.1778)
						)
						(arc
							(start 0.2794 -0.1778)
							(mid 0.249642 -0.249642)
							(end 0.1778 -0.2794)
						)
					)
					(width 0)
					(fill yes)
				)
			)
		)
		(pad "2" smd custom
			(at 0 0.4445 270)
			(size 0.1397 0.1397)
			(layers "F.Cu" "F.Mask" "F.Paste")
			(net "NCT7904_VSEN_P12V_AUX")
			(options
				(clearance outline)
				(anchor circle)
			)
			(primitives
				(gr_poly
					(pts
						(arc
							(start -0.1778 -0.2794)
							(mid -0.249642 -0.249642)
							(end -0.2794 -0.1778)
						)
						(arc
							(start -0.2794 0.1778)
							(mid -0.249642 0.249642)
							(end -0.1778 0.2794)
						)
						(arc
							(start 0.1778 0.2794)
							(mid 0.249642 0.249642)
							(end 0.2794 0.1778)
						)
						(arc
							(start 0.2794 -0.1778)
							(mid 0.249642 -0.249642)
							(end 0.1778 -0.2794)
						)
					)
					(width 0)
					(fill yes)
				)
			)
		)
	)
)
